(kicad_pcb
	(version 20260206)
	(generator "pcbnew")
	(generator_version "10.0")
	(general
		(thickness 1.6)
		(legacy_teardrops no)
	)
	(paper "A4")
	(title_block
		(title "03242023_DA0F0TMBIJ0_F0T_Motherboard_J_brd_V01_OCP.brd")
		(comment 1 "Grand Teton / footprints 3324-3330 of 6105")
	)
	(layers
		(0 "F.Cu" signal "TOP")
		(4 "In1.Cu" signal "GND")
		(6 "In2.Cu" signal "IN1")
		(8 "In3.Cu" signal "GND1")
		(10 "In4.Cu" signal "IN2")
		(12 "In5.Cu" signal "GND2")
		(14 "In6.Cu" signal "IN3")
		(16 "In7.Cu" signal "GND3")
		(18 "In8.Cu" signal "VCC")
		(20 "In9.Cu" signal "VCC1")
		(22 "In10.Cu" signal "GND4")
		(24 "In11.Cu" signal "IN4")
		(26 "In12.Cu" signal "GND5")
		(28 "In13.Cu" signal "IN5")
		(30 "In14.Cu" signal "GND6")
		(32 "In15.Cu" signal "IN6")
		(34 "In16.Cu" signal "GND7")
		(2 "B.Cu" signal "BOTTOM")
		(9 "F.Adhes" user "F.Adhesive")
		(11 "B.Adhes" user "B.Adhesive")
		(13 "F.Paste" user "Package Geometry/Pastemask Top")
		(15 "B.Paste" user "Package Geometry/Pastemask Bottom")
		(5 "F.SilkS" user "Ref Des/Silkscreen Top")
		(7 "B.SilkS" user "Ref Des/Silkscreen Bottom")
		(1 "F.Mask" user "Board Geometry/Soldermask Top")
		(3 "B.Mask" user "Board Geometry/Soldermask Bottom")
		(17 "Dwgs.User" user "User.Drawings")
		(19 "Cmts.User" user "User.Comments")
		(21 "Eco1.User" user "User.Eco1")
		(23 "Eco2.User" user "User.Eco2")
		(25 "Edge.Cuts" user "Board Geometry/Outline")
		(27 "Margin" user)
		(31 "F.CrtYd" user "Package Geometry/Place Bound Top")
		(29 "B.CrtYd" user "Package Geometry/Place Bound Bottom")
		(35 "F.Fab" user "Ref Des/Assembly Top")
		(33 "B.Fab" user "Ref Des/Assembly Bottom")
	)
	(footprint ""
		(layer "F.Cu")
		(at 172.77588 -130.266948 -90)
		(property "Reference" "R1446"
			(at 0 0 270)
			(layer "F.SilkS")
			(hide yes)
			(effects
				(font
					(size 1.27 1.27)
				)
			)
		)
		(property "Value" ""
			(at 0 0 270)
			(layer "F.Fab")
			(effects
				(font
					(size 1.27 1.27)
				)
			)
		)
		(duplicate_pad_numbers_are_jumpers no)
		(fp_line
			(start -0.7874 0.4064)
			(end -0.7874 -0.4064)
			(stroke
				(width 0.1524)
				(type default)
			)
			(layer "F.SilkS")
		)
		(fp_line
			(start 0.7874 0.4064)
			(end -0.7874 0.4064)
			(stroke
				(width 0.1524)
				(type default)
			)
			(layer "F.SilkS")
		)
		(fp_line
			(start -0.7874 -0.4064)
			(end 0.7874 -0.4064)
			(stroke
				(width 0.1524)
				(type default)
			)
			(layer "F.SilkS")
		)
		(fp_line
			(start 0.7874 -0.4064)
			(end 0.7874 0.4064)
			(stroke
				(width 0.1524)
				(type default)
			)
			(layer "F.SilkS")
		)
		(fp_line
			(start -0.67945 0.3048)
			(end -0.67945 -0.305054)
			(stroke
				(width 0.1)
				(type default)
			)
			(layer "F.Fab")
		)
		(fp_line
			(start -0.12065 0.3048)
			(end -0.67945 0.3048)
			(stroke
				(width 0.1)
				(type default)
			)
			(layer "F.Fab")
		)
		(fp_line
			(start 0.120396 0.3048)
			(end 0.120396 0.2794)
			(stroke
				(width 0.1)
				(type default)
			)
			(layer "F.Fab")
		)
		(fp_line
			(start 0.67945 0.3048)
			(end 0.120396 0.3048)
			(stroke
				(width 0.1)
				(type default)
			)
			(layer "F.Fab")
		)
		(fp_line
			(start -0.12065 0.2794)
			(end -0.12065 0.3048)
			(stroke
				(width 0.1)
				(type default)
			)
			(layer "F.Fab")
		)
		(fp_line
			(start 0.120396 0.2794)
			(end -0.12065 0.2794)
			(stroke
				(width 0.1)
				(type default)
			)
			(layer "F.Fab")
		)
		(fp_line
			(start -0.12065 -0.2794)
			(end 0.12065 -0.2794)
			(stroke
				(width 0.1)
				(type default)
			)
			(layer "F.Fab")
		)
		(fp_line
			(start 0.12065 -0.2794)
			(end 0.12065 -0.3048)
			(stroke
				(width 0.1)
				(type default)
			)
			(layer "F.Fab")
		)
		(fp_line
			(start 0.12065 -0.3048)
			(end 0.67945 -0.3048)
			(stroke
				(width 0.1)
				(type default)
			)
			(layer "F.Fab")
		)
		(fp_line
			(start 0.67945 -0.3048)
			(end 0.67945 0.3048)
			(stroke
				(width 0.1)
				(type default)
			)
			(layer "F.Fab")
		)
		(fp_line
			(start -0.67945 -0.305054)
			(end -0.12065 -0.305054)
			(stroke
				(width 0.1)
				(type default)
			)
			(layer "F.Fab")
		)
		(fp_line
			(start -0.12065 -0.305054)
			(end -0.12065 -0.2794)
			(stroke
				(width 0.1)
				(type default)
			)
			(layer "F.Fab")
		)
		(pad "1" smd circle
			(at -0.40005 0 270)
			(size 0 0)
			(layers "F.Cu" "F.Mask" "F.Paste")
			(net "PWRGD_PS_PWROK_PLD_ISO")
		)
		(pad "2" smd circle
			(at 0.40005 0 270)
			(size 0 0)
			(layers "F.Cu" "F.Mask" "F.Paste")
			(net "PWRGD_PS_PWROK_PLD_ISO_R")
		)
	)
	(footprint ""
		(layer "F.Cu")
		(at 86.68893 -74.730356 -90)
		(property "Reference" "R3100"
			(at 0 0 270)
			(layer "F.SilkS")
			(hide yes)
			(effects
				(font
					(size 1.27 1.27)
				)
			)
		)
		(property "Value" ""
			(at 0 0 270)
			(layer "F.Fab")
			(effects
				(font
					(size 1.27 1.27)
				)
			)
		)
		(duplicate_pad_numbers_are_jumpers no)
		(fp_line
			(start -0.7874 0.4064)
			(end -0.7874 -0.4064)
			(stroke
				(width 0.1524)
				(type default)
			)
			(layer "F.SilkS")
		)
		(fp_line
			(start 0.7874 0.4064)
			(end -0.7874 0.4064)
			(stroke
				(width 0.1524)
				(type default)
			)
			(layer "F.SilkS")
		)
		(fp_line
			(start -0.7874 -0.4064)
			(end 0.7874 -0.4064)
			(stroke
				(width 0.1524)
				(type default)
			)
			(layer "F.SilkS")
		)
		(fp_line
			(start 0.7874 -0.4064)
			(end 0.7874 0.4064)
			(stroke
				(width 0.1524)
				(type default)
			)
			(layer "F.SilkS")
		)
		(fp_line
			(start -0.67945 0.3048)
			(end -0.67945 -0.305054)
			(stroke
				(width 0.1)
				(type default)
			)
			(layer "F.Fab")
		)
		(fp_line
			(start -0.12065 0.3048)
			(end -0.67945 0.3048)
			(stroke
				(width 0.1)
				(type default)
			)
			(layer "F.Fab")
		)
		(fp_line
			(start 0.120396 0.3048)
			(end 0.120396 0.2794)
			(stroke
				(width 0.1)
				(type default)
			)
			(layer "F.Fab")
		)
		(fp_line
			(start 0.67945 0.3048)
			(end 0.120396 0.3048)
			(stroke
				(width 0.1)
				(type default)
			)
			(layer "F.Fab")
		)
		(fp_line
			(start -0.12065 0.2794)
			(end -0.12065 0.3048)
			(stroke
				(width 0.1)
				(type default)
			)
			(layer "F.Fab")
		)
		(fp_line
			(start 0.120396 0.2794)
			(end -0.12065 0.2794)
			(stroke
				(width 0.1)
				(type default)
			)
			(layer "F.Fab")
		)
		(fp_line
			(start -0.12065 -0.2794)
			(end 0.12065 -0.2794)
			(stroke
				(width 0.1)
				(type default)
			)
			(layer "F.Fab")
		)
		(fp_line
			(start 0.12065 -0.2794)
			(end 0.12065 -0.3048)
			(stroke
				(width 0.1)
				(type default)
			)
			(layer "F.Fab")
		)
		(fp_line
			(start 0.12065 -0.3048)
			(end 0.67945 -0.3048)
			(stroke
				(width 0.1)
				(type default)
			)
			(layer "F.Fab")
		)
		(fp_line
			(start 0.67945 -0.3048)
			(end 0.67945 0.3048)
			(stroke
				(width 0.1)
				(type default)
			)
			(layer "F.Fab")
		)
		(fp_line
			(start -0.67945 -0.305054)
			(end -0.12065 -0.305054)
			(stroke
				(width 0.1)
				(type default)
			)
			(layer "F.Fab")
		)
		(fp_line
			(start -0.12065 -0.305054)
			(end -0.12065 -0.2794)
			(stroke
				(width 0.1)
				(type default)
			)
			(layer "F.Fab")
		)
		(pad "1" smd circle
			(at -0.40005 0 270)
			(size 0 0)
			(layers "F.Cu" "F.Mask" "F.Paste")
			(net "LED_P3V3")
		)
		(pad "2" smd circle
			(at 0.40005 0 270)
			(size 0 0)
			(layers "F.Cu" "F.Mask" "F.Paste")
			(net "P3V3")
		)
	)
	(footprint ""
		(layer "F.Cu")
		(at 96.959674 -324.445376)
		(property "Reference" "PL31"
			(at -5.761228 7.068566 90)
			(unlocked yes)
			(layer "F.SilkS")
			(effects
				(font
					(size 0.7874 0.5842)
					(thickness 0.1524)
				)
				(justify left)
			)
		)
		(property "Value" ""
			(at 0 0 0)
			(layer "F.Fab")
			(effects
				(font
					(size 1.27 1.27)
				)
			)
		)
		(duplicate_pad_numbers_are_jumpers no)
		(fp_line
			(start -3.750056 -5.500116)
			(end -2.393442 -5.500116)
			(stroke
				(width 0.1524)
				(type default)
			)
			(layer "F.SilkS")
		)
		(fp_line
			(start -3.750056 5.500116)
			(end -3.750056 -5.500116)
			(stroke
				(width 0.1524)
				(type default)
			)
			(layer "F.SilkS")
		)
		(fp_line
			(start -2.393442 5.500116)
			(end -3.750056 5.500116)
			(stroke
				(width 0.1524)
				(type default)
			)
			(layer "F.SilkS")
		)
		(fp_line
			(start 2.393442 5.500116)
			(end 3.750056 5.500116)
			(stroke
				(width 0.1524)
				(type default)
			)
			(layer "F.SilkS")
		)
		(fp_line
			(start 3.750056 -5.500116)
			(end 2.393442 -5.500116)
			(stroke
				(width 0.1524)
				(type default)
			)
			(layer "F.SilkS")
		)
		(fp_line
			(start 3.750056 5.500116)
			(end 3.750056 -5.500116)
			(stroke
				(width 0.1524)
				(type default)
			)
			(layer "F.SilkS")
		)
		(fp_poly
			(pts
				(xy -3.34391 -6.96722) (xy -2.984754 -5.889498) (xy -4.062222 -6.248654)
			)
			(stroke
				(width 0)
				(type default)
			)
			(fill yes)
			(layer "F.SilkS")
		)
		(fp_line
			(start -3.750056 -5.500116)
			(end -3.750056 5.500116)
			(stroke
				(width 0.1)
				(type default)
			)
			(layer "F.Fab")
		)
		(fp_line
			(start -3.750056 5.500116)
			(end 3.750056 5.500116)
			(stroke
				(width 0.1)
				(type default)
			)
			(layer "F.Fab")
		)
		(fp_line
			(start 3.750056 -5.500116)
			(end -3.750056 -5.500116)
			(stroke
				(width 0.1)
				(type default)
			)
			(layer "F.Fab")
		)
		(fp_line
			(start 3.750056 5.500116)
			(end 3.750056 -5.500116)
			(stroke
				(width 0.1)
				(type default)
			)
			(layer "F.Fab")
		)
		(fp_poly
			(pts
				(xy -4.9276 -4.757928) (xy -4.9276 -3.741928) (xy -3.9116 -4.249928)
			)
			(stroke
				(width 0)
				(type default)
			)
			(fill yes)
			(layer "F.Fab")
		)
		(pad "1" smd rect
			(at 0 -4.249928 270)
			(size 2.413 4.5212)
			(layers "F.Cu" "F.Mask" "F.Paste")
			(net "SW_PVCCIN_CPU1_SW1")
		)
		(pad "2" smd rect
			(at 0 -1.175004 270)
			(size 1.3716 4.5212)
			(layers "F.Cu" "F.Mask" "F.Paste")
			(net "IND_P1_CPL1")
		)
		(pad "3" smd rect
			(at 0 1.175004 270)
			(size 1.3716 4.5212)
			(layers "F.Cu" "F.Mask" "F.Paste")
			(net "IND_P1_CPL6")
		)
		(pad "4" smd rect
			(at 0 4.249928 270)
			(size 2.413 4.5212)
			(layers "F.Cu" "F.Mask" "F.Paste")
			(net "PVCCIN_CPU1")
		)
	)
	(footprint ""
		(layer "F.Cu")
		(at 95.94088 -32.626808)
		(property "Reference" "R3229"
			(at 0 0 0)
			(layer "F.SilkS")
			(hide yes)
			(effects
				(font
					(size 1.27 1.27)
				)
			)
		)
		(property "Value" ""
			(at 0 0 0)
			(layer "F.Fab")
			(effects
				(font
					(size 1.27 1.27)
				)
			)
		)
		(duplicate_pad_numbers_are_jumpers no)
		(fp_line
			(start -0.7874 -0.4064)
			(end 0.7874 -0.4064)
			(stroke
				(width 0.1524)
				(type default)
			)
			(layer "F.SilkS")
		)
		(fp_line
			(start -0.7874 0.4064)
			(end -0.7874 -0.4064)
			(stroke
				(width 0.1524)
				(type default)
			)
			(layer "F.SilkS")
		)
		(fp_line
			(start 0.7874 -0.4064)
			(end 0.7874 0.4064)
			(stroke
				(width 0.1524)
				(type default)
			)
			(layer "F.SilkS")
		)
		(fp_line
			(start 0.7874 0.4064)
			(end -0.7874 0.4064)
			(stroke
				(width 0.1524)
				(type default)
			)
			(layer "F.SilkS")
		)
		(fp_line
			(start -0.67945 -0.305054)
			(end -0.12065 -0.305054)
			(stroke
				(width 0.1)
				(type default)
			)
			(layer "F.Fab")
		)
		(fp_line
			(start -0.67945 0.3048)
			(end -0.67945 -0.305054)
			(stroke
				(width 0.1)
				(type default)
			)
			(layer "F.Fab")
		)
		(fp_line
			(start -0.12065 -0.305054)
			(end -0.12065 -0.2794)
			(stroke
				(width 0.1)
				(type default)
			)
			(layer "F.Fab")
		)
		(fp_line
			(start -0.12065 -0.2794)
			(end 0.12065 -0.2794)
			(stroke
				(width 0.1)
				(type default)
			)
			(layer "F.Fab")
		)
		(fp_line
			(start -0.12065 0.2794)
			(end -0.12065 0.3048)
			(stroke
				(width 0.1)
				(type default)
			)
			(layer "F.Fab")
		)
		(fp_line
			(start -0.12065 0.3048)
			(end -0.67945 0.3048)
			(stroke
				(width 0.1)
				(type default)
			)
			(layer "F.Fab")
		)
		(fp_line
			(start 0.120396 0.2794)
			(end -0.12065 0.2794)
			(stroke
				(width 0.1)
				(type default)
			)
			(layer "F.Fab")
		)
		(fp_line
			(start 0.120396 0.3048)
			(end 0.120396 0.2794)
			(stroke
				(width 0.1)
				(type default)
			)
			(layer "F.Fab")
		)
		(fp_line
			(start 0.12065 -0.3048)
			(end 0.67945 -0.3048)
			(stroke
				(width 0.1)
				(type default)
			)
			(layer "F.Fab")
		)
		(fp_line
			(start 0.12065 -0.2794)
			(end 0.12065 -0.3048)
			(stroke
				(width 0.1)
				(type default)
			)
			(layer "F.Fab")
		)
		(fp_line
			(start 0.67945 -0.3048)
			(end 0.67945 0.3048)
			(stroke
				(width 0.1)
				(type default)
			)
			(layer "F.Fab")
		)
		(fp_line
			(start 0.67945 0.3048)
			(end 0.120396 0.3048)
			(stroke
				(width 0.1)
				(type default)
			)
			(layer "F.Fab")
		)
		(pad "1" smd circle
			(at -0.40005 0)
			(size 0 0)
			(layers "F.Cu" "F.Mask" "F.Paste")
			(net "SMB_OCP_V3_2_3V3AUX_BUF_R_SDA")
		)
		(pad "2" smd circle
			(at 0.40005 0)
			(size 0 0)
			(layers "F.Cu" "F.Mask" "F.Paste")
			(net "SMB_OCP_V3_2_3V3AUX_BUF_SDA")
		)
	)
	(footprint ""
		(layer "F.Cu")
		(at 368.915188 -360.043222 90)
		(property "Reference" "PC2001"
			(at 0 0 90)
			(layer "F.SilkS")
			(hide yes)
			(effects
				(font
					(size 1.27 1.27)
				)
			)
		)
		(property "Value" ""
			(at 0 0 90)
			(layer "F.Fab")
			(effects
				(font
					(size 1.27 1.27)
				)
			)
		)
		(duplicate_pad_numbers_are_jumpers no)
		(fp_line
			(start 0.7874 -0.4064)
			(end 0.7874 0.4064)
			(stroke
				(width 0.1524)
				(type default)
			)
			(layer "F.SilkS")
		)
		(fp_line
			(start -0.7874 -0.4064)
			(end 0.7874 -0.4064)
			(stroke
				(width 0.1524)
				(type default)
			)
			(layer "F.SilkS")
		)
		(fp_line
			(start 0.7874 0.4064)
			(end -0.7874 0.4064)
			(stroke
				(width 0.1524)
				(type default)
			)
			(layer "F.SilkS")
		)
		(fp_line
			(start -0.7874 0.4064)
			(end -0.7874 -0.4064)
			(stroke
				(width 0.1524)
				(type default)
			)
			(layer "F.SilkS")
		)
		(fp_line
			(start -0.12065 -0.305054)
			(end -0.12065 -0.2794)
			(stroke
				(width 0.1)
				(type default)
			)
			(layer "F.Fab")
		)
		(fp_line
			(start -0.67945 -0.305054)
			(end -0.12065 -0.305054)
			(stroke
				(width 0.1)
				(type default)
			)
			(layer "F.Fab")
		)
		(fp_line
			(start 0.67945 -0.3048)
			(end 0.67945 0.3048)
			(stroke
				(width 0.1)
				(type default)
			)
			(layer "F.Fab")
		)
		(fp_line
			(start 0.12065 -0.3048)
			(end 0.67945 -0.3048)
			(stroke
				(width 0.1)
				(type default)
			)
			(layer "F.Fab")
		)
		(fp_line
			(start 0.12065 -0.2794)
			(end 0.12065 -0.3048)
			(stroke
				(width 0.1)
				(type default)
			)
			(layer "F.Fab")
		)
		(fp_line
			(start -0.12065 -0.2794)
			(end 0.12065 -0.2794)
			(stroke
				(width 0.1)
				(type default)
			)
			(layer "F.Fab")
		)
		(fp_line
			(start 0.120396 0.2794)
			(end -0.12065 0.2794)
			(stroke
				(width 0.1)
				(type default)
			)
			(layer "F.Fab")
		)
		(fp_line
			(start -0.12065 0.2794)
			(end -0.12065 0.3048)
			(stroke
				(width 0.1)
				(type default)
			)
			(layer "F.Fab")
		)
		(fp_line
			(start 0.67945 0.3048)
			(end 0.120396 0.3048)
			(stroke
				(width 0.1)
				(type default)
			)
			(layer "F.Fab")
		)
		(fp_line
			(start 0.120396 0.3048)
			(end 0.120396 0.2794)
			(stroke
				(width 0.1)
				(type default)
			)
			(layer "F.Fab")
		)
		(fp_line
			(start -0.12065 0.3048)
			(end -0.67945 0.3048)
			(stroke
				(width 0.1)
				(type default)
			)
			(layer "F.Fab")
		)
		(fp_line
			(start -0.67945 0.3048)
			(end -0.67945 -0.305054)
			(stroke
				(width 0.1)
				(type default)
			)
			(layer "F.Fab")
		)
		(pad "1" smd circle
			(at -0.40005 0 90)
			(size 0 0)
			(layers "F.Cu" "F.Mask" "F.Paste")
			(net "PVPP_HBM_CPU0_REF")
		)
		(pad "2" smd circle
			(at 0.40005 0 90)
			(size 0 0)
			(layers "F.Cu" "F.Mask" "F.Paste")
			(net "GND")
		)
	)
	(footprint ""
		(layer "F.Cu")
		(at 432.265836 -17.612614 90)
		(property "Reference" "C869"
			(at 0 0 90)
			(layer "F.SilkS")
			(hide yes)
			(effects
				(font
					(size 1.27 1.27)
				)
			)
		)
		(property "Value" ""
			(at 0 0 90)
			(layer "F.Fab")
			(effects
				(font
					(size 1.27 1.27)
				)
			)
		)
		(duplicate_pad_numbers_are_jumpers no)
		(fp_line
			(start 0.299974 -0.150114)
			(end 0.299974 0.150114)
			(stroke
				(width 0.1)
				(type default)
			)
			(layer "F.Fab")
		)
		(fp_line
			(start -0.299974 -0.150114)
			(end 0.299974 -0.150114)
			(stroke
				(width 0.1)
				(type default)
			)
			(layer "F.Fab")
		)
		(fp_line
			(start 0.299974 0.150114)
			(end -0.299974 0.150114)
			(stroke
				(width 0.1)
				(type default)
			)
			(layer "F.Fab")
		)
		(fp_line
			(start -0.299974 0.150114)
			(end -0.299974 -0.150114)
			(stroke
				(width 0.1)
				(type default)
			)
			(layer "F.Fab")
		)
		(pad "1" smd rect
			(at -0.2667 0 90)
			(size 0.3048 0.381)
			(layers "F.Cu" "F.Mask" "F.Paste")
			(net "P5E_CPU0_PE1_TX_C_DP<0>")
		)
		(pad "2" smd rect
			(at 0.2667 0 90)
			(size 0.3048 0.381)
			(layers "F.Cu" "F.Mask" "F.Paste")
			(net "P5E_CPU0_PE1_TX_DP<0>")
		)
	)
	(footprint ""
		(layer "F.Cu")
		(at 366.48263 -241.976656 -90)
		(property "Reference" "C1033"
			(at 0 0 270)
			(layer "F.SilkS")
			(hide yes)
			(effects
				(font
					(size 1.27 1.27)
				)
			)
		)
		(property "Value" ""
			(at 0 0 270)
			(layer "F.Fab")
			(effects
				(font
					(size 1.27 1.27)
				)
			)
		)
		(duplicate_pad_numbers_are_jumpers no)
		(fp_line
			(start -0.7874 0.4064)
			(end -0.7874 -0.4064)
			(stroke
				(width 0.1524)
				(type default)
			)
			(layer "F.SilkS")
		)
		(fp_line
			(start 0.7874 0.4064)
			(end -0.7874 0.4064)
			(stroke
				(width 0.1524)
				(type default)
			)
			(layer "F.SilkS")
		)
		(fp_line
			(start -0.7874 -0.4064)
			(end 0.7874 -0.4064)
			(stroke
				(width 0.1524)
				(type default)
			)
			(layer "F.SilkS")
		)
		(fp_line
			(start 0.7874 -0.4064)
			(end 0.7874 0.4064)
			(stroke
				(width 0.1524)
				(type default)
			)
			(layer "F.SilkS")
		)
		(fp_line
			(start -0.67945 0.3048)
			(end -0.67945 -0.305054)
			(stroke
				(width 0.1)
				(type default)
			)
			(layer "F.Fab")
		)
		(fp_line
			(start -0.12065 0.3048)
			(end -0.67945 0.3048)
			(stroke
				(width 0.1)
				(type default)
			)
			(layer "F.Fab")
		)
		(fp_line
			(start 0.120396 0.3048)
			(end 0.120396 0.2794)
			(stroke
				(width 0.1)
				(type default)
			)
			(layer "F.Fab")
		)
		(fp_line
			(start 0.67945 0.3048)
			(end 0.120396 0.3048)
			(stroke
				(width 0.1)
				(type default)
			)
			(layer "F.Fab")
		)
		(fp_line
			(start -0.12065 0.2794)
			(end -0.12065 0.3048)
			(stroke
				(width 0.1)
				(type default)
			)
			(layer "F.Fab")
		)
		(fp_line
			(start 0.120396 0.2794)
			(end -0.12065 0.2794)
			(stroke
				(width 0.1)
				(type default)
			)
			(layer "F.Fab")
		)
		(fp_line
			(start -0.12065 -0.2794)
			(end 0.12065 -0.2794)
			(stroke
				(width 0.1)
				(type default)
			)
			(layer "F.Fab")
		)
		(fp_line
			(start 0.12065 -0.2794)
			(end 0.12065 -0.3048)
			(stroke
				(width 0.1)
				(type default)
			)
			(layer "F.Fab")
		)
		(fp_line
			(start 0.12065 -0.3048)
			(end 0.67945 -0.3048)
			(stroke
				(width 0.1)
				(type default)
			)
			(layer "F.Fab")
		)
		(fp_line
			(start 0.67945 -0.3048)
			(end 0.67945 0.3048)
			(stroke
				(width 0.1)
				(type default)
			)
			(layer "F.Fab")
		)
		(fp_line
			(start -0.67945 -0.305054)
			(end -0.12065 -0.305054)
			(stroke
				(width 0.1)
				(type default)
			)
			(layer "F.Fab")
		)
		(fp_line
			(start -0.12065 -0.305054)
			(end -0.12065 -0.2794)
			(stroke
				(width 0.1)
				(type default)
			)
			(layer "F.Fab")
		)
		(pad "1" smd circle
			(at -0.40005 0 270)
			(size 0 0)
			(layers "F.Cu" "F.Mask" "F.Paste")
			(net "PVCCIN_CPU0")
		)
		(pad "2" smd circle
			(at 0.40005 0 270)
			(size 0 0)
			(layers "F.Cu" "F.Mask" "F.Paste")
			(net "GND")
		)
	)
)
